(kicad_pcb
	(version 20241229)
	(generator "pcbnew")
	(generator_version "9.0")
	(general
		(thickness 1.711)
		(legacy_teardrops no)
	)
	(paper "A4")
	(title_block
		(title "Antmicro Baseboard for Jetson AGX Thor")
		(date "2026-02-18")
		(rev "1.1.0")
		(company "Antmicro Ltd")
		(comment 1 "www.antmicro.com")
		(comment 9 "footprints 320-324 of 1170")
	)
	(layers
		(0 "F.Cu" signal)
		(4 "In1.Cu" signal)
		(6 "In2.Cu" signal)
		(8 "In3.Cu" signal)
		(10 "In4.Cu" jumper)
		(12 "In5.Cu" signal)
		(14 "In6.Cu" signal)
		(16 "In7.Cu" signal)
		(18 "In8.Cu" signal)
		(2 "B.Cu" signal)
		(9 "F.Adhes" user "F.Adhesive")
		(11 "B.Adhes" user "B.Adhesive")
		(13 "F.Paste" user)
		(15 "B.Paste" user)
		(5 "F.SilkS" user "F.Silkscreen")
		(7 "B.SilkS" user "B.Silkscreen")
		(1 "F.Mask" user)
		(3 "B.Mask" user)
		(17 "Dwgs.User" user "User.Drawings")
		(19 "Cmts.User" user "User.Comments")
		(21 "Eco1.User" user "User.Eco1")
		(23 "Eco2.User" user "User.Eco2")
		(25 "Edge.Cuts" user)
		(27 "Margin" user)
		(31 "F.CrtYd" user "F.Courtyard")
		(29 "B.CrtYd" user "B.Courtyard")
		(35 "F.Fab" user)
		(33 "B.Fab" user)
	)
	(footprint "antmicro-footprints:R_0603_1608Metric"
		(layer "F.Cu")
		(at 136.4 60.4 -90)
		(descr "Resistor SMD 0603")
		(tags "resistor SMD 0603")
		(property "Reference" "R63"
			(at -1.1 -0.73 90)
			(layer "F.SilkS")
			(effects
				(font
					(size 0.7 0.7)
					(thickness 0.15)
				)
				(justify right top)
			)
		)
		(property "Value" "R_0R_22.4A_0603"
			(at 0 1.6 90)
			(layer "F.Fab")
			(effects
				(font
					(size 0.7 0.7)
					(thickness 0.15)
				)
				(justify right top)
			)
		)
		(property "Datasheet" "https://fscdn.rohm.com/en/products/databook/datasheet/passive/resistor/chip_resistor/pmr-jpw-e.pdf"
			(at 0 0 90)
			(layer "F.Fab")
			(hide yes)
			(effects
				(font
					(size 1.27 1.27)
					(thickness 0.15)
				)
			)
		)
		(property "Description" "SMD Chip Resistor"
			(at 0 0 90)
			(layer "F.Fab")
			(hide yes)
			(effects
				(font
					(size 1.27 1.27)
					(thickness 0.15)
				)
			)
		)
		(property "Manufacturer" "ROHM Semiconductor"
			(at 0 0 270)
			(unlocked yes)
			(layer "F.Fab")
			(hide yes)
			(effects
				(font
					(size 1 1)
					(thickness 0.15)
				)
			)
		)
		(property "MPN" "PMR03EZPJ000"
			(at 0 0 270)
			(unlocked yes)
			(layer "F.Fab")
			(hide yes)
			(effects
				(font
					(size 1 1)
					(thickness 0.15)
				)
			)
		)
		(property "Val" "0R"
			(at 0 0 270)
			(unlocked yes)
			(layer "F.Fab")
			(hide yes)
			(effects
				(font
					(size 1 1)
					(thickness 0.15)
				)
			)
		)
		(property "License" "Apache-2.0"
			(at 0 0 270)
			(unlocked yes)
			(layer "F.Fab")
			(hide yes)
			(effects
				(font
					(size 1 1)
					(thickness 0.15)
				)
			)
		)
		(property "Author" "Antmicro"
			(at 0 0 270)
			(unlocked yes)
			(layer "F.Fab")
			(hide yes)
			(effects
				(font
					(size 1 1)
					(thickness 0.15)
				)
			)
		)
		(property "Tolerance" "template_tolerance"
			(at 0 0 270)
			(unlocked yes)
			(layer "F.Fab")
			(hide yes)
			(effects
				(font
					(size 1 1)
					(thickness 0.15)
				)
			)
		)
		(property "Max. Curr." "22.4A"
			(at 0 0 90)
			(unlocked yes)
			(layer "F.Fab")
			(hide yes)
			(effects
				(font
					(size 1 1)
					(thickness 0.15)
				)
			)
		)
		(sheetname "/Power/")
		(sheetfile "power.kicad_sch")
		(attr smd)
		(fp_line
			(start -0.15 0.4)
			(end 0.15 0.4)
			(stroke
				(width 0.15)
				(type solid)
			)
			(layer "F.SilkS")
		)
		(fp_line
			(start -0.15 -0.4)
			(end 0.15 -0.4)
			(stroke
				(width 0.15)
				(type solid)
			)
			(layer "F.SilkS")
		)
		(fp_poly
			(pts
				(xy -1.25 -0.65) (xy 1.25 -0.65) (xy 1.25 0.65) (xy -1.25 0.65)
			)
			(stroke
				(width 0.05)
				(type solid)
			)
			(fill no)
			(layer "F.CrtYd")
		)
		(fp_poly
			(pts
				(xy -0.8 -0.4) (xy 0.8 -0.4) (xy 0.8 0.4) (xy -0.8 0.4)
			)
			(stroke
				(width 0.15)
				(type solid)
			)
			(fill no)
			(layer "F.Fab")
		)
		(fp_text user "${REFERENCE}"
			(at -1.25 3.898 90)
			(layer "F.Fab")
			(effects
				(font
					(size 0.7 0.7)
					(thickness 0.15)
				)
				(justify right top)
			)
		)
		(fp_text user "Author: Antmicro"
			(at -1.25 4.9 90)
			(layer "F.Fab")
			(effects
				(font
					(size 0.7 0.7)
					(thickness 0.15)
				)
				(justify right top)
			)
		)
		(fp_text user "License: Apache-2.0"
			(at -1.249999 5.9 90)
			(layer "F.Fab")
			(effects
				(font
					(size 0.7 0.7)
					(thickness 0.15)
				)
				(justify right top)
			)
		)
		(pad "1" smd roundrect
			(at -0.7 0 270)
			(size 0.8 1)
			(layers "F.Cu" "F.Mask" "F.Paste")
			(roundrect_rratio 0.2)
			(net 31 "/Power/3V3_LDO")
			(pintype "passive")
		)
		(pad "2" smd roundrect
			(at 0.7 0 270)
			(size 0.8 1)
			(layers "F.Cu" "F.Mask" "F.Paste")
			(roundrect_rratio 0.2)
			(net 4 "+3V3_AON")
			(pintype "passive")
		)
	)
	(footprint "antmicro-footprints:XDFN-2_1x0.60mm"
		(layer "F.Cu")
		(at 211.25 55.5 -90)
		(property "Reference" "D54"
			(at 1 0.5 90)
			(layer "F.SilkS")
			(effects
				(font
					(size 0.7 0.7)
					(thickness 0.15)
				)
				(justify left bottom)
			)
		)
		(property "Value" "TPD1E0B04_XDFN-2"
			(at 0 1.5 90)
			(layer "F.Fab")
			(effects
				(font
					(size 0.7 0.7)
					(thickness 0.15)
				)
				(justify right top)
			)
		)
		(property "Datasheet" "https://www.ti.com/general/docs/suppproductinfo.tsp?distId=26&gotoUrl=https://www.ti.com/lit/gpn/tpd1e0b04"
			(at 0 0 90)
			(layer "F.Fab")
			(hide yes)
			(effects
				(font
					(size 1.27 1.27)
					(thickness 0.15)
				)
			)
		)
		(property "Description" "Bidirectional TVS, 8 kV,  XDFN-2, 3.6 V, 0.18 pF"
			(at 0 0 90)
			(layer "F.Fab")
			(hide yes)
			(effects
				(font
					(size 1.27 1.27)
					(thickness 0.15)
				)
			)
		)
		(property "MPN" "TPD1E0B04DPYR"
			(at 0 0 90)
			(layer "F.Fab")
			(hide yes)
			(effects
				(font
					(size 1.27 1.27)
					(thickness 0.15)
				)
			)
		)
		(property "Manufacturer" "Texas Instruments"
			(at 0 0 90)
			(layer "F.Fab")
			(hide yes)
			(effects
				(font
					(size 1.27 1.27)
					(thickness 0.15)
				)
			)
		)
		(property "Author" "Antmicro"
			(at 0 0 270)
			(unlocked yes)
			(layer "F.Fab")
			(hide yes)
			(effects
				(font
					(size 1 1)
					(thickness 0.15)
				)
			)
		)
		(property "License" "Apache-2.0"
			(at 0 0 270)
			(unlocked yes)
			(layer "F.Fab")
			(hide yes)
			(effects
				(font
					(size 1 1)
					(thickness 0.15)
				)
			)
		)
		(sheetname "/SoM_Power/")
		(sheetfile "som_power.kicad_sch")
		(attr smd)
		(fp_poly
			(pts
				(xy -0.725 -0.475) (xy 0.725 -0.475) (xy 0.725 0.475) (xy -0.725 0.475)
			)
			(stroke
				(width 0.05)
				(type solid)
			)
			(fill no)
			(layer "F.CrtYd")
		)
		(fp_poly
			(pts
				(xy -0.55 -0.35) (xy 0.55 -0.35) (xy 0.55 0.35) (xy -0.55 0.35)
			)
			(stroke
				(width 0.15)
				(type solid)
			)
			(fill no)
			(layer "F.Fab")
		)
		(fp_text user "License: Apache-2.0"
			(at -0.799999 5.6 90)
			(layer "F.Fab")
			(effects
				(font
					(size 0.7 0.7)
					(thickness 0.15)
				)
				(justify right top)
			)
		)
		(fp_text user "${REFERENCE}"
			(at -0.8 3.2 90)
			(layer "F.Fab")
			(effects
				(font
					(size 0.7 0.7)
					(thickness 0.15)
				)
				(justify right top)
			)
		)
		(fp_text user "Author: Antmicro"
			(at -0.8 4.4 90)
			(layer "F.Fab")
			(effects
				(font
					(size 0.7 0.7)
					(thickness 0.15)
				)
				(justify right top)
			)
		)
		(pad "1" smd roundrect
			(at -0.350999 0 270)
			(size 0.3 0.5)
			(layers "F.Cu" "F.Mask" "F.Paste")
			(roundrect_rratio 0.25)
			(net 1 "GND")
			(pinfunction "C")
			(pintype "passive")
		)
		(pad "2" smd roundrect
			(at 0.349 0 270)
			(size 0.3 0.5)
			(layers "F.Cu" "F.Mask" "F.Paste")
			(roundrect_rratio 0.25)
			(net 610 "/SoM_Power/~{PWR_BTN}")
			(pinfunction "A")
			(pintype "passive")
		)
	)
	(footprint "antmicro-footprints:R_0402_1005Metric"
		(layer "F.Cu")
		(at 232.540532 108.71 180)
		(descr "Resistor SMD 0402")
		(tags "resistor SMD 0402")
		(property "Reference" "R271"
			(at -1.359468 -0.79 0)
			(layer "F.SilkS")
			(effects
				(font
					(size 0.7 0.7)
					(thickness 0.15)
				)
				(justify right top)
			)
		)
		(property "Value" "R_470R_0402"
			(at -1.011843 1.772046 0)
			(layer "F.Fab")
			(effects
				(font
					(size 0.7 0.7)
					(thickness 0.15)
				)
				(justify right top)
			)
		)
		(property "Datasheet" "https://www.bourns.com/docs/product-datasheets/cr.pdf"
			(at 0 0 0)
			(layer "F.Fab")
			(hide yes)
			(effects
				(font
					(size 1.27 1.27)
					(thickness 0.15)
				)
			)
		)
		(property "Description" "SMD Chip Resistor, 470 ohm, ± 1%, 62.5 mW, 0402 [1005 Metric], Thick Film, General Purpose"
			(at 0 0 0)
			(layer "F.Fab")
			(hide yes)
			(effects
				(font
					(size 1.27 1.27)
					(thickness 0.15)
				)
			)
		)
		(property "Manufacturer" "Bourns"
			(at 0 0 180)
			(unlocked yes)
			(layer "F.Fab")
			(hide yes)
			(effects
				(font
					(size 1 1)
					(thickness 0.15)
				)
			)
		)
		(property "MPN" "CR0402-FX-4700GLF"
			(at 0 0 180)
			(unlocked yes)
			(layer "F.Fab")
			(hide yes)
			(effects
				(font
					(size 1 1)
					(thickness 0.15)
				)
			)
		)
		(property "Val" "470R"
			(at 0 0 180)
			(unlocked yes)
			(layer "F.Fab")
			(hide yes)
			(effects
				(font
					(size 1 1)
					(thickness 0.15)
				)
			)
		)
		(property "License" "Apache-2.0"
			(at 0 0 180)
			(unlocked yes)
			(layer "F.Fab")
			(hide yes)
			(effects
				(font
					(size 1 1)
					(thickness 0.15)
				)
			)
		)
		(property "Author" "Antmicro"
			(at 0 0 180)
			(unlocked yes)
			(layer "F.Fab")
			(hide yes)
			(effects
				(font
					(size 1 1)
					(thickness 0.15)
				)
			)
		)
		(property "Tolerance" "1%"
			(at 0 0 180)
			(unlocked yes)
			(layer "F.Fab")
			(hide yes)
			(effects
				(font
					(size 1 1)
					(thickness 0.15)
				)
			)
		)
		(sheetname "/Recovery USB/")
		(sheetfile "recovery_usb.kicad_sch")
		(attr smd)
		(fp_poly
			(pts
				(xy -0.925 -0.47) (xy 0.925 -0.47) (xy 0.925 0.47) (xy -0.925 0.47)
			)
			(stroke
				(width 0.05)
				(type default)
			)
			(fill no)
			(layer "F.CrtYd")
		)
		(fp_poly
			(pts
				(xy -0.5 -0.25) (xy 0.5 -0.25) (xy 0.5 0.25) (xy -0.5 0.25)
			)
			(stroke
				(width 0.15)
				(type solid)
			)
			(fill no)
			(layer "F.Fab")
		)
		(fp_text user "${REFERENCE}"
			(at -0.95 3.168 0)
			(layer "F.Fab")
			(effects
				(font
					(size 0.7 0.7)
					(thickness 0.15)
				)
				(justify right top)
			)
		)
		(fp_text user "Author: Antmicro"
			(at -0.95 4.169 0)
			(layer "F.Fab")
			(effects
				(font
					(size 0.7 0.7)
					(thickness 0.15)
				)
				(justify right top)
			)
		)
		(fp_text user "License: Apache-2.0"
			(at -0.949999 5.169 0)
			(layer "F.Fab")
			(effects
				(font
					(size 0.7 0.7)
					(thickness 0.15)
				)
				(justify right top)
			)
		)
		(pad "1" smd roundrect
			(at -0.48 0 180)
			(size 0.59 0.64)
			(layers "F.Cu" "F.Mask" "F.Paste")
			(roundrect_rratio 0.25)
			(net 1391 "Net-(D51-A)")
			(pintype "passive")
		)
		(pad "2" smd roundrect
			(at 0.48 0 180)
			(size 0.59 0.64)
			(layers "F.Cu" "F.Mask" "F.Paste")
			(roundrect_rratio 0.25)
			(net 287 "/Recovery USB/USBC2_VBUS")
			(pintype "passive")
		)
	)
	(footprint "antmicro-footprints:R_0402_1005Metric"
		(layer "F.Cu")
		(at 181.85 139.33 -90)
		(descr "Resistor SMD 0402")
		(tags "resistor SMD 0402")
		(property "Reference" "R15"
			(at -5.83 -2.25 90)
			(layer "F.SilkS")
			(effects
				(font
					(size 0.7 0.7)
					(thickness 0.15)
				)
				(justify right top)
			)
		)
		(property "Value" "R_51k_0402"
			(at -1.011843 1.772047 90)
			(layer "F.Fab")
			(effects
				(font
					(size 0.7 0.7)
					(thickness 0.15)
				)
				(justify right top)
			)
		)
		(property "Datasheet" "https://www.bourns.com/docs/product-datasheets/cr.pdf"
			(at 0 0 90)
			(layer "F.Fab")
			(hide yes)
			(effects
				(font
					(size 1.27 1.27)
					(thickness 0.15)
				)
			)
		)
		(property "Description" "SMD Chip Resistor, 51 kohm, ± 1%, 63 mW, 0402 [1005 Metric], Thick Film, General Purpose"
			(at 0 0 90)
			(layer "F.Fab")
			(hide yes)
			(effects
				(font
					(size 1.27 1.27)
					(thickness 0.15)
				)
			)
		)
		(property "MPN" "CR0402-FX-5102GLF"
			(at 0 0 270)
			(unlocked yes)
			(layer "F.Fab")
			(hide yes)
			(effects
				(font
					(size 1 1)
					(thickness 0.15)
				)
			)
		)
		(property "Manufacturer" "Bourns"
			(at 0 0 270)
			(unlocked yes)
			(layer "F.Fab")
			(hide yes)
			(effects
				(font
					(size 1 1)
					(thickness 0.15)
				)
			)
		)
		(property "License" "Apache-2.0"
			(at 0 0 270)
			(unlocked yes)
			(layer "F.Fab")
			(hide yes)
			(effects
				(font
					(size 1 1)
					(thickness 0.15)
				)
			)
		)
		(property "Author" "Antmicro"
			(at 0 0 270)
			(unlocked yes)
			(layer "F.Fab")
			(hide yes)
			(effects
				(font
					(size 1 1)
					(thickness 0.15)
				)
			)
		)
		(property "Val" "51k"
			(at 0 0 270)
			(unlocked yes)
			(layer "F.Fab")
			(hide yes)
			(effects
				(font
					(size 1 1)
					(thickness 0.15)
				)
			)
		)
		(property "Tolerance" "1%"
			(at 0 0 270)
			(unlocked yes)
			(layer "F.Fab")
			(hide yes)
			(effects
				(font
					(size 1 1)
					(thickness 0.15)
				)
			)
		)
		(sheetname "/DCDC/")
		(sheetfile "dcdc.kicad_sch")
		(attr smd)
		(fp_rect
			(start -0.925 -0.47)
			(end 0.925 0.47)
			(stroke
				(width 0.05)
				(type default)
			)
			(fill no)
			(layer "F.CrtYd")
		)
		(fp_rect
			(start -0.5 -0.25)
			(end 0.5 0.25)
			(stroke
				(width 0.15)
				(type solid)
			)
			(fill no)
			(layer "F.Fab")
		)
		(fp_text user "Author: Antmicro"
			(at -0.95 4.169 90)
			(layer "F.Fab")
			(effects
				(font
					(size 0.7 0.7)
					(thickness 0.15)
				)
				(justify right top)
			)
		)
		(fp_text user "License: Apache-2.0"
			(at -0.95 5.169 90)
			(layer "F.Fab")
			(effects
				(font
					(size 0.7 0.7)
					(thickness 0.15)
				)
				(justify right top)
			)
		)
		(fp_text user "${REFERENCE}"
			(at -0.95 3.168 90)
			(layer "F.Fab")
			(effects
				(font
					(size 0.7 0.7)
					(thickness 0.15)
				)
				(justify right top)
			)
		)
		(pad "1" smd roundrect
			(at -0.48 0 270)
			(size 0.59 0.64)
			(layers "F.Cu" "F.Mask" "F.Paste")
			(roundrect_rratio 0.25)
			(net 1 "GND")
			(pintype "passive")
		)
		(pad "2" smd roundrect
			(at 0.48 0 270)
			(size 0.59 0.64)
			(layers "F.Cu" "F.Mask" "F.Paste")
			(roundrect_rratio 0.25)
			(net 1205 "/DCDC/12V_MODE2")
			(pintype "passive")
		)
	)
	(footprint "antmicro-footprints:C_0805_2012Metric"
		(layer "F.Cu")
		(at 173.17 73.32 -90)
		(descr "Capacitor SMD 0805")
		(tags "capacitor SMD 0805")
		(property "Reference" "C303"
			(at 1.78449 -1.468678 90)
			(layer "F.SilkS")
			(effects
				(font
					(size 0.7 0.7)
					(thickness 0.15)
				)
				(justify right top)
			)
		)
		(property "Value" "C_22u_25V_0805"
			(at -2.055717 1.963152 90)
			(layer "F.Fab")
			(effects
				(font
					(size 0.7 0.7)
					(thickness 0.15)
				)
				(justify right top)
			)
		)
		(property "Datasheet" "https://product.samsungsem.com/mlcc/CL21A226MAYNNN.do"
			(at 0 0 90)
			(layer "F.Fab")
			(hide yes)
			(effects
				(font
					(size 1.27 1.27)
					(thickness 0.15)
				)
			)
		)
		(property "Description" "SMT Multilayer Ceramic Capacitor, 22uF, +/-20%, 25V, X5R, 0805 [2012 Metric]"
			(at 0 0 90)
			(layer "F.Fab")
			(hide yes)
			(effects
				(font
					(size 1.27 1.27)
					(thickness 0.15)
				)
			)
		)
		(property "MPN" "CL21A226MAYNNNE"
			(at 0 0 270)
			(unlocked yes)
			(layer "F.Fab")
			(hide yes)
			(effects
				(font
					(size 1 1)
					(thickness 0.15)
				)
			)
		)
		(property "Manufacturer" "Samsung Electro-Mechanics"
			(at 0 0 270)
			(unlocked yes)
			(layer "F.Fab")
			(hide yes)
			(effects
				(font
					(size 1 1)
					(thickness 0.15)
				)
			)
		)
		(property "License" "Apache-2.0"
			(at 0 0 270)
			(unlocked yes)
			(layer "F.Fab")
			(hide yes)
			(effects
				(font
					(size 1 1)
					(thickness 0.15)
				)
			)
		)
		(property "Author" "Antmicro"
			(at 0 0 270)
			(unlocked yes)
			(layer "F.Fab")
			(hide yes)
			(effects
				(font
					(size 1 1)
					(thickness 0.15)
				)
			)
		)
		(property "Val" "22u"
			(at 0 0 270)
			(unlocked yes)
			(layer "F.Fab")
			(hide yes)
			(effects
				(font
					(size 1 1)
					(thickness 0.15)
				)
			)
		)
		(property "Voltage" "25V"
			(at 0 0 270)
			(unlocked yes)
			(layer "F.Fab")
			(hide yes)
			(effects
				(font
					(size 1 1)
					(thickness 0.15)
				)
			)
		)
		(property "Dielectric" "X5R"
			(at 0 0 270)
			(unlocked yes)
			(layer "F.Fab")
			(hide yes)
			(effects
				(font
					(size 1 1)
					(thickness 0.15)
				)
			)
		)
		(property "Public" "False"
			(at 0 0 270)
			(unlocked yes)
			(layer "F.Fab")
			(hide yes)
			(effects
				(font
					(size 1 1)
					(thickness 0.15)
				)
			)
		)
		(component_classes
			(class "DCDC_20V")
		)
		(sheetname "/DCDC/")
		(sheetfile "dcdc.kicad_sch")
		(attr smd)
		(fp_line
			(start -0.3 0.7)
			(end 0.3 0.7)
			(stroke
				(width 0.15)
				(type solid)
			)
			(layer "F.SilkS")
		)
		(fp_line
			(start -0.3 -0.7)
			(end 0.3 -0.7)
			(stroke
				(width 0.15)
				(type solid)
			)
			(layer "F.SilkS")
		)
		(fp_rect
			(start 1.95 -0.9)
			(end -1.95 0.9)
			(stroke
				(width 0.05)
				(type default)
			)
			(fill no)
			(layer "F.CrtYd")
		)
		(fp_rect
			(start -0.95 -0.675)
			(end 0.95 0.675)
			(stroke
				(width 0.15)
				(type solid)
			)
			(fill no)
			(layer "F.Fab")
		)
		(fp_text user "${REFERENCE}"
			(at -1.9 3.947 90)
			(layer "F.Fab")
			(effects
				(font
					(size 0.7 0.7)
					(thickness 0.15)
				)
				(justify right top)
			)
		)
		(fp_text user "Author: Antmicro"
			(at -1.9 5.947 90)
			(layer "F.Fab")
			(effects
				(font
					(size 0.7 0.7)
					(thickness 0.15)
				)
				(justify right top)
			)
		)
		(fp_text user "License: Apache-2.0"
			(at -1.9 4.947 90)
			(layer "F.Fab")
			(effects
				(font
					(size 0.7 0.7)
					(thickness 0.15)
				)
				(justify right top)
			)
		)
		(pad "1" smd roundrect
			(at -1.1 0 270)
			(size 1.2 1.3)
			(layers "F.Cu" "F.Mask" "F.Paste")
			(roundrect_rratio 0.25)
			(net 1 "GND")
			(pintype "passive")
		)
		(pad "2" smd roundrect
			(at 1.1 0 270)
			(size 1.2 1.3)
			(layers "F.Cu" "F.Mask" "F.Paste")
			(roundrect_rratio 0.25)
			(net 1105 "/DCDC/20V_OUT")
			(pintype "passive")
		)
	)
)
